(kicad_pcb
	(version 20260206)
	(generator "pcbnew")
	(generator_version "10.0")
	(general
		(thickness 1.6)
		(legacy_teardrops no)
	)
	(paper "A4")
	(title_block
		(title "03242023_DA0F0TMBIJ0_F0T_Motherboard_J_brd_V01_OCP.brd")
		(comment 1 "Grand Teton / footprints 4033-4038 of 6105")
	)
	(layers
		(0 "F.Cu" signal "TOP")
		(4 "In1.Cu" signal "GND")
		(6 "In2.Cu" signal "IN1")
		(8 "In3.Cu" signal "GND1")
		(10 "In4.Cu" signal "IN2")
		(12 "In5.Cu" signal "GND2")
		(14 "In6.Cu" signal "IN3")
		(16 "In7.Cu" signal "GND3")
		(18 "In8.Cu" signal "VCC")
		(20 "In9.Cu" signal "VCC1")
		(22 "In10.Cu" signal "GND4")
		(24 "In11.Cu" signal "IN4")
		(26 "In12.Cu" signal "GND5")
		(28 "In13.Cu" signal "IN5")
		(30 "In14.Cu" signal "GND6")
		(32 "In15.Cu" signal "IN6")
		(34 "In16.Cu" signal "GND7")
		(2 "B.Cu" signal "BOTTOM")
		(9 "F.Adhes" user "F.Adhesive")
		(11 "B.Adhes" user "B.Adhesive")
		(13 "F.Paste" user "Package Geometry/Pastemask Top")
		(15 "B.Paste" user "Package Geometry/Pastemask Bottom")
		(5 "F.SilkS" user "Ref Des/Silkscreen Top")
		(7 "B.SilkS" user "Ref Des/Silkscreen Bottom")
		(1 "F.Mask" user "Board Geometry/Soldermask Top")
		(3 "B.Mask" user "Board Geometry/Soldermask Bottom")
		(17 "Dwgs.User" user "User.Drawings")
		(19 "Cmts.User" user "User.Comments")
		(21 "Eco1.User" user "User.Eco1")
		(23 "Eco2.User" user "User.Eco2")
		(25 "Edge.Cuts" user "Board Geometry/Outline")
		(27 "Margin" user)
		(31 "F.CrtYd" user "Package Geometry/Place Bound Top")
		(29 "B.CrtYd" user "Package Geometry/Place Bound Bottom")
		(35 "F.Fab" user "Ref Des/Assembly Top")
		(33 "B.Fab" user "Ref Des/Assembly Bottom")
	)
	(footprint ""
		(layer "F.Cu")
		(at 451.327012 -30.397958 -90)
		(property "Reference" "PD101"
			(at -0.14224 -1.991868 0)
			(unlocked yes)
			(layer "F.SilkS")
			(effects
				(font
					(size 0.7874 0.5842)
					(thickness 0.1524)
				)
				(justify left)
			)
		)
		(property "Value" ""
			(at 0 0 270)
			(layer "F.Fab")
			(effects
				(font
					(size 1.27 1.27)
				)
			)
		)
		(duplicate_pad_numbers_are_jumpers no)
		(fp_line
			(start -2.250186 0.999998)
			(end 2.631186 0.999998)
			(stroke
				(width 0.1524)
				(type default)
			)
			(layer "F.SilkS")
		)
		(fp_line
			(start 2.631186 0.999998)
			(end 2.631186 -0.999998)
			(stroke
				(width 0.1524)
				(type default)
			)
			(layer "F.SilkS")
		)
		(fp_line
			(start -0.381 0.3302)
			(end -0.381 -0.4318)
			(stroke
				(width 0.1524)
				(type default)
			)
			(layer "F.SilkS")
		)
		(fp_line
			(start -0.381 -0.0508)
			(end -0.6604 -0.0508)
			(stroke
				(width 0.1524)
				(type default)
			)
			(layer "F.SilkS")
		)
		(fp_line
			(start 0.381 -0.0508)
			(end -0.381 0.3302)
			(stroke
				(width 0.1524)
				(type default)
			)
			(layer "F.SilkS")
		)
		(fp_line
			(start 0.381 -0.0508)
			(end 0.635 -0.0508)
			(stroke
				(width 0.1524)
				(type default)
			)
			(layer "F.SilkS")
		)
		(fp_line
			(start -0.381 -0.4318)
			(end 0.381 -0.0508)
			(stroke
				(width 0.1524)
				(type default)
			)
			(layer "F.SilkS")
		)
		(fp_line
			(start 0.381 -0.4318)
			(end 0.381 0.3302)
			(stroke
				(width 0.1524)
				(type default)
			)
			(layer "F.SilkS")
		)
		(fp_line
			(start -2.250186 -0.999998)
			(end -2.250186 0.999998)
			(stroke
				(width 0.1524)
				(type default)
			)
			(layer "F.SilkS")
		)
		(fp_line
			(start 2.631186 -0.999998)
			(end -2.250186 -0.999998)
			(stroke
				(width 0.1524)
				(type default)
			)
			(layer "F.SilkS")
		)
		(fp_rect
			(start 2.6162 1.016)
			(end 2.1844 -0.9652)
			(stroke
				(width 0)
				(type default)
			)
			(fill yes)
			(layer "F.SilkS")
		)
		(fp_line
			(start -1.450086 0.999998)
			(end 1.450086 0.999998)
			(stroke
				(width 0.1)
				(type default)
			)
			(layer "F.Fab")
		)
		(fp_line
			(start 1.450086 0.999998)
			(end 1.450086 -0.999998)
			(stroke
				(width 0.1)
				(type default)
			)
			(layer "F.Fab")
		)
		(fp_line
			(start -1.450086 -0.999998)
			(end -1.450086 0.999998)
			(stroke
				(width 0.1)
				(type default)
			)
			(layer "F.Fab")
		)
		(fp_line
			(start 1.450086 -0.999998)
			(end -1.450086 -0.999998)
			(stroke
				(width 0.1)
				(type default)
			)
			(layer "F.Fab")
		)
		(fp_text user "+"
			(at -4.56057 -0.126238 270)
			(unlocked yes)
			(layer "F.SilkS")
			(effects
				(font
					(size 1.905 1.4224)
					(thickness 0.1524)
				)
				(justify left)
			)
		)
		(fp_text user "-"
			(at 2.4384 -0.22225 270)
			(unlocked yes)
			(layer "F.SilkS")
			(effects
				(font
					(size 1.905 1.4224)
					(thickness 0.1524)
				)
				(justify left)
			)
		)
		(fp_text user "+"
			(at -3.4798 -0.22225 270)
			(unlocked yes)
			(layer "F.Fab")
			(effects
				(font
					(size 1.905 1.4224)
					(thickness 0.1524)
				)
				(justify left)
			)
		)
		(fp_text user "-"
			(at 2.4384 -0.22225 270)
			(unlocked yes)
			(layer "F.Fab")
			(effects
				(font
					(size 1.905 1.4224)
					(thickness 0.1524)
				)
				(justify left)
			)
		)
		(pad "A" smd rect
			(at -1.450086 0 270)
			(size 1.3208 1.4224)
			(layers "F.Cu" "F.Mask" "F.Paste")
			(net "GND")
		)
		(pad "C" smd rect
			(at 1.450086 0 270)
			(size 1.3208 1.4224)
			(layers "F.Cu" "F.Mask" "F.Paste")
			(net "P12V_AUX")
		)
	)
	(footprint ""
		(layer "F.Cu")
		(at 334.174846 -18.79727 -90)
		(property "Reference" "C608"
			(at 0 0 270)
			(layer "F.SilkS")
			(hide yes)
			(effects
				(font
					(size 1.27 1.27)
				)
			)
		)
		(property "Value" ""
			(at 0 0 270)
			(layer "F.Fab")
			(effects
				(font
					(size 1.27 1.27)
				)
			)
		)
		(duplicate_pad_numbers_are_jumpers no)
		(fp_line
			(start -0.7874 0.4064)
			(end -0.7874 -0.4064)
			(stroke
				(width 0.1524)
				(type default)
			)
			(layer "F.SilkS")
		)
		(fp_line
			(start 0.7874 0.4064)
			(end -0.7874 0.4064)
			(stroke
				(width 0.1524)
				(type default)
			)
			(layer "F.SilkS")
		)
		(fp_line
			(start -0.7874 -0.4064)
			(end 0.7874 -0.4064)
			(stroke
				(width 0.1524)
				(type default)
			)
			(layer "F.SilkS")
		)
		(fp_line
			(start 0.7874 -0.4064)
			(end 0.7874 0.4064)
			(stroke
				(width 0.1524)
				(type default)
			)
			(layer "F.SilkS")
		)
		(fp_line
			(start -0.67945 0.3048)
			(end -0.67945 -0.305054)
			(stroke
				(width 0.1)
				(type default)
			)
			(layer "F.Fab")
		)
		(fp_line
			(start -0.12065 0.3048)
			(end -0.67945 0.3048)
			(stroke
				(width 0.1)
				(type default)
			)
			(layer "F.Fab")
		)
		(fp_line
			(start 0.120396 0.3048)
			(end 0.120396 0.2794)
			(stroke
				(width 0.1)
				(type default)
			)
			(layer "F.Fab")
		)
		(fp_line
			(start 0.67945 0.3048)
			(end 0.120396 0.3048)
			(stroke
				(width 0.1)
				(type default)
			)
			(layer "F.Fab")
		)
		(fp_line
			(start -0.12065 0.2794)
			(end -0.12065 0.3048)
			(stroke
				(width 0.1)
				(type default)
			)
			(layer "F.Fab")
		)
		(fp_line
			(start 0.120396 0.2794)
			(end -0.12065 0.2794)
			(stroke
				(width 0.1)
				(type default)
			)
			(layer "F.Fab")
		)
		(fp_line
			(start -0.12065 -0.2794)
			(end 0.12065 -0.2794)
			(stroke
				(width 0.1)
				(type default)
			)
			(layer "F.Fab")
		)
		(fp_line
			(start 0.12065 -0.2794)
			(end 0.12065 -0.3048)
			(stroke
				(width 0.1)
				(type default)
			)
			(layer "F.Fab")
		)
		(fp_line
			(start 0.12065 -0.3048)
			(end 0.67945 -0.3048)
			(stroke
				(width 0.1)
				(type default)
			)
			(layer "F.Fab")
		)
		(fp_line
			(start 0.67945 -0.3048)
			(end 0.67945 0.3048)
			(stroke
				(width 0.1)
				(type default)
			)
			(layer "F.Fab")
		)
		(fp_line
			(start -0.67945 -0.305054)
			(end -0.12065 -0.305054)
			(stroke
				(width 0.1)
				(type default)
			)
			(layer "F.Fab")
		)
		(fp_line
			(start -0.12065 -0.305054)
			(end -0.12065 -0.2794)
			(stroke
				(width 0.1)
				(type default)
			)
			(layer "F.Fab")
		)
		(pad "1" smd circle
			(at -0.40005 0 270)
			(size 0 0)
			(layers "F.Cu" "F.Mask" "F.Paste")
			(net "PGPPA_AUX")
		)
		(pad "2" smd circle
			(at 0.40005 0 270)
			(size 0 0)
			(layers "F.Cu" "F.Mask" "F.Paste")
			(net "GND")
		)
	)
	(footprint ""
		(layer "F.Cu")
		(at 174.635922 -24.601932)
		(property "Reference" "PR4014"
			(at 0 0 0)
			(layer "F.SilkS")
			(hide yes)
			(effects
				(font
					(size 1.27 1.27)
				)
			)
		)
		(property "Value" ""
			(at 0 0 0)
			(layer "F.Fab")
			(effects
				(font
					(size 1.27 1.27)
				)
			)
		)
		(duplicate_pad_numbers_are_jumpers no)
		(fp_line
			(start -1.2954 -0.5842)
			(end 1.2954 -0.5842)
			(stroke
				(width 0.1524)
				(type default)
			)
			(layer "F.SilkS")
		)
		(fp_line
			(start -1.2954 0.5842)
			(end -1.2954 -0.5842)
			(stroke
				(width 0.1524)
				(type default)
			)
			(layer "F.SilkS")
		)
		(fp_line
			(start 1.2954 -0.5842)
			(end 1.2954 0.5842)
			(stroke
				(width 0.1524)
				(type default)
			)
			(layer "F.SilkS")
		)
		(fp_line
			(start 1.2954 0.5842)
			(end -1.2954 0.5842)
			(stroke
				(width 0.1524)
				(type default)
			)
			(layer "F.SilkS")
		)
		(fp_line
			(start -1.1938 -0.406654)
			(end -0.8636 -0.406654)
			(stroke
				(width 0.1)
				(type default)
			)
			(layer "F.Fab")
		)
		(fp_line
			(start -1.1938 0.4064)
			(end -1.1938 -0.406654)
			(stroke
				(width 0.1)
				(type default)
			)
			(layer "F.Fab")
		)
		(fp_line
			(start -0.8636 -0.4572)
			(end 0.8636 -0.4572)
			(stroke
				(width 0.1)
				(type default)
			)
			(layer "F.Fab")
		)
		(fp_line
			(start -0.8636 -0.406654)
			(end -0.8636 -0.4572)
			(stroke
				(width 0.1)
				(type default)
			)
			(layer "F.Fab")
		)
		(fp_line
			(start -0.8636 0.4064)
			(end -1.1938 0.4064)
			(stroke
				(width 0.1)
				(type default)
			)
			(layer "F.Fab")
		)
		(fp_line
			(start -0.8636 0.4318)
			(end -0.8636 0.4064)
			(stroke
				(width 0.1)
				(type default)
			)
			(layer "F.Fab")
		)
		(fp_line
			(start -0.8636 0.4572)
			(end -0.8636 0.4318)
			(stroke
				(width 0.1)
				(type default)
			)
			(layer "F.Fab")
		)
		(fp_line
			(start 0.8636 -0.4572)
			(end 0.8636 -0.406654)
			(stroke
				(width 0.1)
				(type default)
			)
			(layer "F.Fab")
		)
		(fp_line
			(start 0.8636 -0.406654)
			(end 1.1938 -0.406654)
			(stroke
				(width 0.1)
				(type default)
			)
			(layer "F.Fab")
		)
		(fp_line
			(start 0.8636 0.4064)
			(end 0.8636 0.4572)
			(stroke
				(width 0.1)
				(type default)
			)
			(layer "F.Fab")
		)
		(fp_line
			(start 0.8636 0.4572)
			(end -0.8636 0.4572)
			(stroke
				(width 0.1)
				(type default)
			)
			(layer "F.Fab")
		)
		(fp_line
			(start 1.1938 -0.406654)
			(end 1.1938 0.4064)
			(stroke
				(width 0.1)
				(type default)
			)
			(layer "F.Fab")
		)
		(fp_line
			(start 1.1938 0.4064)
			(end 0.8636 0.4064)
			(stroke
				(width 0.1)
				(type default)
			)
			(layer "F.Fab")
		)
		(pad "1" smd rect
			(at -0.7366 0 270)
			(size 0.7112 0.8128)
			(layers "F.Cu" "F.Mask" "F.Paste")
			(net "P12V_AUX")
		)
		(pad "2" smd rect
			(at 0.7366 0 270)
			(size 0.7112 0.8128)
			(layers "F.Cu" "F.Mask" "F.Paste")
			(net "P12V_SCM_AVIN_PD")
		)
	)
	(footprint ""
		(layer "F.Cu")
		(at 226.733608 -408.887422)
		(property "Reference" "PR3989"
			(at 0 0 0)
			(layer "F.SilkS")
			(hide yes)
			(effects
				(font
					(size 1.27 1.27)
				)
			)
		)
		(property "Value" ""
			(at 0 0 0)
			(layer "F.Fab")
			(effects
				(font
					(size 1.27 1.27)
				)
			)
		)
		(duplicate_pad_numbers_are_jumpers no)
		(fp_line
			(start -0.7874 -0.4064)
			(end 0.7874 -0.4064)
			(stroke
				(width 0.1524)
				(type default)
			)
			(layer "F.SilkS")
		)
		(fp_line
			(start -0.7874 0.4064)
			(end -0.7874 -0.4064)
			(stroke
				(width 0.1524)
				(type default)
			)
			(layer "F.SilkS")
		)
		(fp_line
			(start 0.7874 -0.4064)
			(end 0.7874 0.4064)
			(stroke
				(width 0.1524)
				(type default)
			)
			(layer "F.SilkS")
		)
		(fp_line
			(start 0.7874 0.4064)
			(end -0.7874 0.4064)
			(stroke
				(width 0.1524)
				(type default)
			)
			(layer "F.SilkS")
		)
		(fp_line
			(start -0.67945 -0.305054)
			(end -0.12065 -0.305054)
			(stroke
				(width 0.1)
				(type default)
			)
			(layer "F.Fab")
		)
		(fp_line
			(start -0.67945 0.3048)
			(end -0.67945 -0.305054)
			(stroke
				(width 0.1)
				(type default)
			)
			(layer "F.Fab")
		)
		(fp_line
			(start -0.12065 -0.305054)
			(end -0.12065 -0.2794)
			(stroke
				(width 0.1)
				(type default)
			)
			(layer "F.Fab")
		)
		(fp_line
			(start -0.12065 -0.2794)
			(end 0.12065 -0.2794)
			(stroke
				(width 0.1)
				(type default)
			)
			(layer "F.Fab")
		)
		(fp_line
			(start -0.12065 0.2794)
			(end -0.12065 0.3048)
			(stroke
				(width 0.1)
				(type default)
			)
			(layer "F.Fab")
		)
		(fp_line
			(start -0.12065 0.3048)
			(end -0.67945 0.3048)
			(stroke
				(width 0.1)
				(type default)
			)
			(layer "F.Fab")
		)
		(fp_line
			(start 0.120396 0.2794)
			(end -0.12065 0.2794)
			(stroke
				(width 0.1)
				(type default)
			)
			(layer "F.Fab")
		)
		(fp_line
			(start 0.120396 0.3048)
			(end 0.120396 0.2794)
			(stroke
				(width 0.1)
				(type default)
			)
			(layer "F.Fab")
		)
		(fp_line
			(start 0.12065 -0.3048)
			(end 0.67945 -0.3048)
			(stroke
				(width 0.1)
				(type default)
			)
			(layer "F.Fab")
		)
		(fp_line
			(start 0.12065 -0.2794)
			(end 0.12065 -0.3048)
			(stroke
				(width 0.1)
				(type default)
			)
			(layer "F.Fab")
		)
		(fp_line
			(start 0.67945 -0.3048)
			(end 0.67945 0.3048)
			(stroke
				(width 0.1)
				(type default)
			)
			(layer "F.Fab")
		)
		(fp_line
			(start 0.67945 0.3048)
			(end 0.120396 0.3048)
			(stroke
				(width 0.1)
				(type default)
			)
			(layer "F.Fab")
		)
		(pad "1" smd circle
			(at -0.40005 0)
			(size 0 0)
			(layers "F.Cu" "F.Mask" "F.Paste")
			(net "HSC_SCREF")
		)
		(pad "2" smd circle
			(at 0.40005 0)
			(size 0 0)
			(layers "F.Cu" "F.Mask" "F.Paste")
			(net "HSC_SCREF_4")
		)
	)
	(footprint ""
		(layer "F.Cu")
		(at 36.947348 -128.659382)
		(property "Reference" "R2574"
			(at 0 0 0)
			(layer "F.SilkS")
			(hide yes)
			(effects
				(font
					(size 1.27 1.27)
				)
			)
		)
		(property "Value" ""
			(at 0 0 0)
			(layer "F.Fab")
			(effects
				(font
					(size 1.27 1.27)
				)
			)
		)
		(duplicate_pad_numbers_are_jumpers no)
		(fp_line
			(start -0.7874 -0.4064)
			(end 0.7874 -0.4064)
			(stroke
				(width 0.1524)
				(type default)
			)
			(layer "F.SilkS")
		)
		(fp_line
			(start -0.7874 0.4064)
			(end -0.7874 -0.4064)
			(stroke
				(width 0.1524)
				(type default)
			)
			(layer "F.SilkS")
		)
		(fp_line
			(start 0.7874 -0.4064)
			(end 0.7874 0.4064)
			(stroke
				(width 0.1524)
				(type default)
			)
			(layer "F.SilkS")
		)
		(fp_line
			(start 0.7874 0.4064)
			(end -0.7874 0.4064)
			(stroke
				(width 0.1524)
				(type default)
			)
			(layer "F.SilkS")
		)
		(fp_line
			(start -0.67945 -0.305054)
			(end -0.12065 -0.305054)
			(stroke
				(width 0.1)
				(type default)
			)
			(layer "F.Fab")
		)
		(fp_line
			(start -0.67945 0.3048)
			(end -0.67945 -0.305054)
			(stroke
				(width 0.1)
				(type default)
			)
			(layer "F.Fab")
		)
		(fp_line
			(start -0.12065 -0.305054)
			(end -0.12065 -0.2794)
			(stroke
				(width 0.1)
				(type default)
			)
			(layer "F.Fab")
		)
		(fp_line
			(start -0.12065 -0.2794)
			(end 0.12065 -0.2794)
			(stroke
				(width 0.1)
				(type default)
			)
			(layer "F.Fab")
		)
		(fp_line
			(start -0.12065 0.2794)
			(end -0.12065 0.3048)
			(stroke
				(width 0.1)
				(type default)
			)
			(layer "F.Fab")
		)
		(fp_line
			(start -0.12065 0.3048)
			(end -0.67945 0.3048)
			(stroke
				(width 0.1)
				(type default)
			)
			(layer "F.Fab")
		)
		(fp_line
			(start 0.120396 0.2794)
			(end -0.12065 0.2794)
			(stroke
				(width 0.1)
				(type default)
			)
			(layer "F.Fab")
		)
		(fp_line
			(start 0.120396 0.3048)
			(end 0.120396 0.2794)
			(stroke
				(width 0.1)
				(type default)
			)
			(layer "F.Fab")
		)
		(fp_line
			(start 0.12065 -0.3048)
			(end 0.67945 -0.3048)
			(stroke
				(width 0.1)
				(type default)
			)
			(layer "F.Fab")
		)
		(fp_line
			(start 0.12065 -0.2794)
			(end 0.12065 -0.3048)
			(stroke
				(width 0.1)
				(type default)
			)
			(layer "F.Fab")
		)
		(fp_line
			(start 0.67945 -0.3048)
			(end 0.67945 0.3048)
			(stroke
				(width 0.1)
				(type default)
			)
			(layer "F.Fab")
		)
		(fp_line
			(start 0.67945 0.3048)
			(end 0.120396 0.3048)
			(stroke
				(width 0.1)
				(type default)
			)
			(layer "F.Fab")
		)
		(pad "1" smd circle
			(at -0.40005 0)
			(size 0 0)
			(layers "F.Cu" "F.Mask" "F.Paste")
			(net "IRQ_PVCCFA_CPU1_VRHOT_N")
		)
		(pad "2" smd circle
			(at 0.40005 0)
			(size 0 0)
			(layers "F.Cu" "F.Mask" "F.Paste")
			(net "IRQ_PVCCFA_CPU1_VRHOT_R_N")
		)
	)
	(footprint ""
		(layer "F.Cu")
		(at 424.204892 -381.345948)
		(property "Reference" "R2828"
			(at 0 0 0)
			(layer "F.SilkS")
			(hide yes)
			(effects
				(font
					(size 1.27 1.27)
				)
			)
		)
		(property "Value" ""
			(at 0 0 0)
			(layer "F.Fab")
			(effects
				(font
					(size 1.27 1.27)
				)
			)
		)
		(duplicate_pad_numbers_are_jumpers no)
		(fp_line
			(start -0.7874 -0.4064)
			(end 0.7874 -0.4064)
			(stroke
				(width 0.1524)
				(type default)
			)
			(layer "F.SilkS")
		)
		(fp_line
			(start -0.7874 0.4064)
			(end -0.7874 -0.4064)
			(stroke
				(width 0.1524)
				(type default)
			)
			(layer "F.SilkS")
		)
		(fp_line
			(start 0.7874 -0.4064)
			(end 0.7874 0.4064)
			(stroke
				(width 0.1524)
				(type default)
			)
			(layer "F.SilkS")
		)
		(fp_line
			(start 0.7874 0.4064)
			(end -0.7874 0.4064)
			(stroke
				(width 0.1524)
				(type default)
			)
			(layer "F.SilkS")
		)
		(fp_line
			(start -0.67945 -0.305054)
			(end -0.12065 -0.305054)
			(stroke
				(width 0.1)
				(type default)
			)
			(layer "F.Fab")
		)
		(fp_line
			(start -0.67945 0.3048)
			(end -0.67945 -0.305054)
			(stroke
				(width 0.1)
				(type default)
			)
			(layer "F.Fab")
		)
		(fp_line
			(start -0.12065 -0.305054)
			(end -0.12065 -0.2794)
			(stroke
				(width 0.1)
				(type default)
			)
			(layer "F.Fab")
		)
		(fp_line
			(start -0.12065 -0.2794)
			(end 0.12065 -0.2794)
			(stroke
				(width 0.1)
				(type default)
			)
			(layer "F.Fab")
		)
		(fp_line
			(start -0.12065 0.2794)
			(end -0.12065 0.3048)
			(stroke
				(width 0.1)
				(type default)
			)
			(layer "F.Fab")
		)
		(fp_line
			(start -0.12065 0.3048)
			(end -0.67945 0.3048)
			(stroke
				(width 0.1)
				(type default)
			)
			(layer "F.Fab")
		)
		(fp_line
			(start 0.120396 0.2794)
			(end -0.12065 0.2794)
			(stroke
				(width 0.1)
				(type default)
			)
			(layer "F.Fab")
		)
		(fp_line
			(start 0.120396 0.3048)
			(end 0.120396 0.2794)
			(stroke
				(width 0.1)
				(type default)
			)
			(layer "F.Fab")
		)
		(fp_line
			(start 0.12065 -0.3048)
			(end 0.67945 -0.3048)
			(stroke
				(width 0.1)
				(type default)
			)
			(layer "F.Fab")
		)
		(fp_line
			(start 0.12065 -0.2794)
			(end 0.12065 -0.3048)
			(stroke
				(width 0.1)
				(type default)
			)
			(layer "F.Fab")
		)
		(fp_line
			(start 0.67945 -0.3048)
			(end 0.67945 0.3048)
			(stroke
				(width 0.1)
				(type default)
			)
			(layer "F.Fab")
		)
		(fp_line
			(start 0.67945 0.3048)
			(end 0.120396 0.3048)
			(stroke
				(width 0.1)
				(type default)
			)
			(layer "F.Fab")
		)
		(pad "1" smd circle
			(at -0.40005 0)
			(size 0 0)
			(layers "F.Cu" "F.Mask" "F.Paste")
			(net "P3V3_AUX")
		)
		(pad "2" smd circle
			(at 0.40005 0)
			(size 0 0)
			(layers "F.Cu" "F.Mask" "F.Paste")
			(net "RST_BMC_FROM_SWB_N")
		)
	)
)
